# T6G (Grand Teton) — schematic netlist excerpt (pin names and nets, part order shuffled) for the footprints in the layout excerpt that follows; sources: Cadence DE-HDL packaged netlist, KiCad conversion of 04192023_DAF0TMB3IC0_F0TG_MB_C_brd_V02_OCP.brd

PC6578_2  Q_CAP  3300PF 50V 10% X7R  pkg 0402  page 363 : A = SW_P12V_AUX_P0V9_RETIMER_CPU0_FLT ; B = GND
PR267  Q_RES  5.6 1% CHIP  pkg 0402LF  page 219 : A = SW_PVDDCR_CPU1_P1_BOOT3 ; B = SW_PVDDCR_CPU1_P1_BOOT3_R

(kicad_pcb
	(version 20260206)
	(generator "pcbnew")
	(generator_version "10.0")
	(general
		(thickness 1.6)
		(legacy_teardrops no)
	)
	(paper "A4")
	(title_block
		(title "04192023_DAF0TMB3IC0_F0TG_MB_C_brd_V02_OCP.brd")
		(comment 1 "Grand Teton / footprints 906-907 of 8354")
	)
	(layers
		(0 "F.Cu" signal "TOP")
		(4 "In1.Cu" signal "GND")
		(6 "In2.Cu" signal "IN1")
		(8 "In3.Cu" signal "GND1")
		(10 "In4.Cu" signal "IN2")
		(12 "In5.Cu" signal "GND2")
		(14 "In6.Cu" signal "IN3")
		(16 "In7.Cu" signal "GND3")
		(18 "In8.Cu" signal "VCC")
		(20 "In9.Cu" signal "VCC1")
		(22 "In10.Cu" signal "GND4")
		(24 "In11.Cu" signal "IN4")
		(26 "In12.Cu" signal "GND5")
		(28 "In13.Cu" signal "IN5")
		(30 "In14.Cu" signal "GND6")
		(32 "In15.Cu" signal "IN6")
		(34 "In16.Cu" signal "GND7")
		(2 "B.Cu" signal "BOTTOM")
		(9 "F.Adhes" user "F.Adhesive")
		(11 "B.Adhes" user "B.Adhesive")
		(13 "F.Paste" user "Package Geometry/Pastemask Top")
		(15 "B.Paste" user "Package Geometry/Pastemask Bottom")
		(5 "F.SilkS" user "Ref Des/Silkscreen Top")
		(7 "B.SilkS" user "Ref Des/Silkscreen Bottom")
		(1 "F.Mask" user "Board Geometry/Soldermask Top")
		(3 "B.Mask" user "Board Geometry/Soldermask Bottom")
		(17 "Dwgs.User" user "User.Drawings")
		(19 "Cmts.User" user "User.Comments")
		(21 "Eco1.User" user "User.Eco1")
		(23 "Eco2.User" user "User.Eco2")
		(25 "Edge.Cuts" user "Board Geometry/Outline")
		(27 "Margin" user)
		(31 "F.CrtYd" user "Package Geometry/Place Bound Top")
		(29 "B.CrtYd" user "Package Geometry/Place Bound Bottom")
		(35 "F.Fab" user "Ref Des/Assembly Top")
		(33 "B.Fab" user "Ref Des/Assembly Bottom")
	)
	(footprint ""
		(layer "F.Cu")
		(at 71.16826 -339.651848 90)
		(property "Reference" "PR267"
			(at 0 0 90)
			(layer "F.SilkS")
			(hide yes)
			(effects
				(font
					(size 1.27 1.27)
				)
			)
		)
		(property "Value" ""
			(at 0 0 90)
			(layer "F.Fab")
			(effects
				(font
					(size 1.27 1.27)
				)
			)
		)
		(duplicate_pad_numbers_are_jumpers no)
		(fp_line
			(start 0.7874 -0.4064)
			(end 0.7874 0.4064)
			(stroke
				(width 0.1524)
				(type default)
			)
			(layer "F.SilkS")
		)
		(fp_line
			(start -0.7874 -0.4064)
			(end 0.7874 -0.4064)
			(stroke
				(width 0.1524)
				(type default)
			)
			(layer "F.SilkS")
		)
		(fp_line
			(start 0.7874 0.4064)
			(end -0.7874 0.4064)
			(stroke
				(width 0.1524)
				(type default)
			)
			(layer "F.SilkS")
		)
		(fp_line
			(start -0.7874 0.4064)
			(end -0.7874 -0.4064)
			(stroke
				(width 0.1524)
				(type default)
			)
			(layer "F.SilkS")
		)
		(fp_line
			(start -0.12065 -0.305054)
			(end -0.12065 -0.2794)
			(stroke
				(width 0.1)
				(type default)
			)
			(layer "F.Fab")
		)
		(fp_line
			(start -0.67945 -0.305054)
			(end -0.12065 -0.305054)
			(stroke
				(width 0.1)
				(type default)
			)
			(layer "F.Fab")
		)
		(fp_line
			(start 0.67945 -0.3048)
			(end 0.67945 0.3048)
			(stroke
				(width 0.1)
				(type default)
			)
			(layer "F.Fab")
		)
		(fp_line
			(start 0.12065 -0.3048)
			(end 0.67945 -0.3048)
			(stroke
				(width 0.1)
				(type default)
			)
			(layer "F.Fab")
		)
		(fp_line
			(start 0.12065 -0.2794)
			(end 0.12065 -0.3048)
			(stroke
				(width 0.1)
				(type default)
			)
			(layer "F.Fab")
		)
		(fp_line
			(start -0.12065 -0.2794)
			(end 0.12065 -0.2794)
			(stroke
				(width 0.1)
				(type default)
			)
			(layer "F.Fab")
		)
		(fp_line
			(start 0.120396 0.2794)
			(end -0.12065 0.2794)
			(stroke
				(width 0.1)
				(type default)
			)
			(layer "F.Fab")
		)
		(fp_line
			(start -0.12065 0.2794)
			(end -0.12065 0.3048)
			(stroke
				(width 0.1)
				(type default)
			)
			(layer "F.Fab")
		)
		(fp_line
			(start 0.67945 0.3048)
			(end 0.120396 0.3048)
			(stroke
				(width 0.1)
				(type default)
			)
			(layer "F.Fab")
		)
		(fp_line
			(start 0.120396 0.3048)
			(end 0.120396 0.2794)
			(stroke
				(width 0.1)
				(type default)
			)
			(layer "F.Fab")
		)
		(fp_line
			(start -0.12065 0.3048)
			(end -0.67945 0.3048)
			(stroke
				(width 0.1)
				(type default)
			)
			(layer "F.Fab")
		)
		(fp_line
			(start -0.67945 0.3048)
			(end -0.67945 -0.305054)
			(stroke
				(width 0.1)
				(type default)
			)
			(layer "F.Fab")
		)
		(pad "1" smd circle
			(at -0.40005 0 90)
			(size 0 0)
			(layers "F.Cu" "F.Mask" "F.Paste")
			(net "SW_PVDDCR_CPU1_P1_BOOT3")
		)
		(pad "2" smd circle
			(at 0.40005 0 90)
			(size 0 0)
			(layers "F.Cu" "F.Mask" "F.Paste")
			(net "SW_PVDDCR_CPU1_P1_BOOT3_R")
		)
	)
	(footprint ""
		(layer "F.Cu")
		(at 455.524616 -403.12467 180)
		(property "Reference" "PC6578_2"
			(at 0 0 180)
			(layer "F.SilkS")
			(hide yes)
			(effects
				(font
					(size 1.27 1.27)
				)
			)
		)
		(property "Value" ""
			(at 0 0 180)
			(layer "F.Fab")
			(effects
				(font
					(size 1.27 1.27)
				)
			)
		)
		(duplicate_pad_numbers_are_jumpers no)
		(fp_line
			(start 0.7874 0.4064)
			(end -0.7874 0.4064)
			(stroke
				(width 0.1524)
				(type default)
			)
			(layer "F.SilkS")
		)
		(fp_line
			(start 0.7874 -0.4064)
			(end 0.7874 0.4064)
			(stroke
				(width 0.1524)
				(type default)
			)
			(layer "F.SilkS")
		)
		(fp_line
			(start -0.7874 0.4064)
			(end -0.7874 -0.4064)
			(stroke
				(width 0.1524)
				(type default)
			)
			(layer "F.SilkS")
		)
		(fp_line
			(start -0.7874 -0.4064)
			(end 0.7874 -0.4064)
			(stroke
				(width 0.1524)
				(type default)
			)
			(layer "F.SilkS")
		)
		(fp_line
			(start 0.67945 0.3048)
			(end 0.120396 0.3048)
			(stroke
				(width 0.1)
				(type default)
			)
			(layer "F.Fab")
		)
		(fp_line
			(start 0.67945 -0.3048)
			(end 0.67945 0.3048)
			(stroke
				(width 0.1)
				(type default)
			)
			(layer "F.Fab")
		)
		(fp_line
			(start 0.12065 -0.2794)
			(end 0.12065 -0.3048)
			(stroke
				(width 0.1)
				(type default)
			)
			(layer "F.Fab")
		)
		(fp_line
			(start 0.12065 -0.3048)
			(end 0.67945 -0.3048)
			(stroke
				(width 0.1)
				(type default)
			)
			(layer "F.Fab")
		)
		(fp_line
			(start 0.120396 0.3048)
			(end 0.120396 0.2794)
			(stroke
				(width 0.1)
				(type default)
			)
			(layer "F.Fab")
		)
		(fp_line
			(start 0.120396 0.2794)
			(end -0.12065 0.2794)
			(stroke
				(width 0.1)
				(type default)
			)
			(layer "F.Fab")
		)
		(fp_line
			(start -0.12065 0.3048)
			(end -0.67945 0.3048)
			(stroke
				(width 0.1)
				(type default)
			)
			(layer "F.Fab")
		)
		(fp_line
			(start -0.12065 0.2794)
			(end -0.12065 0.3048)
			(stroke
				(width 0.1)
				(type default)
			)
			(layer "F.Fab")
		)
		(fp_line
			(start -0.12065 -0.2794)
			(end 0.12065 -0.2794)
			(stroke
				(width 0.1)
				(type default)
			)
			(layer "F.Fab")
		)
		(fp_line
			(start -0.12065 -0.305054)
			(end -0.12065 -0.2794)
			(stroke
				(width 0.1)
				(type default)
			)
			(layer "F.Fab")
		)
		(fp_line
			(start -0.67945 0.3048)
			(end -0.67945 -0.305054)
			(stroke
				(width 0.1)
				(type default)
			)
			(layer "F.Fab")
		)
		(fp_line
			(start -0.67945 -0.305054)
			(end -0.12065 -0.305054)
			(stroke
				(width 0.1)
				(type default)
			)
			(layer "F.Fab")
		)
		(pad "1" smd circle
			(at -0.40005 0 180)
			(size 0 0)
			(layers "F.Cu" "F.Mask" "F.Paste")
			(net "SW_P12V_AUX_P0V9_RETIMER_CPU0_FLT")
		)
		(pad "2" smd circle
			(at 0.40005 0 180)
			(size 0 0)
			(layers "F.Cu" "F.Mask" "F.Paste")
			(net "GND")
		)
	)
)
